(kicad_pcb
	(version 20260206)
	(generator "pcbnew")
	(generator_version "10.0")
	(general
		(thickness 1.6)
		(legacy_teardrops no)
	)
	(paper "A4")
	(title_block
		(title "04192023_DAF0TMB3IC0_F0TG_MB_C_brd_V02_OCP.brd")
		(comment 1 "Grand Teton / footprints 2942-2949 of 8354")
	)
	(layers
		(0 "F.Cu" signal "TOP")
		(4 "In1.Cu" signal "GND")
		(6 "In2.Cu" signal "IN1")
		(8 "In3.Cu" signal "GND1")
		(10 "In4.Cu" signal "IN2")
		(12 "In5.Cu" signal "GND2")
		(14 "In6.Cu" signal "IN3")
		(16 "In7.Cu" signal "GND3")
		(18 "In8.Cu" signal "VCC")
		(20 "In9.Cu" signal "VCC1")
		(22 "In10.Cu" signal "GND4")
		(24 "In11.Cu" signal "IN4")
		(26 "In12.Cu" signal "GND5")
		(28 "In13.Cu" signal "IN5")
		(30 "In14.Cu" signal "GND6")
		(32 "In15.Cu" signal "IN6")
		(34 "In16.Cu" signal "GND7")
		(2 "B.Cu" signal "BOTTOM")
		(9 "F.Adhes" user "F.Adhesive")
		(11 "B.Adhes" user "B.Adhesive")
		(13 "F.Paste" user "Package Geometry/Pastemask Top")
		(15 "B.Paste" user "Package Geometry/Pastemask Bottom")
		(5 "F.SilkS" user "Ref Des/Silkscreen Top")
		(7 "B.SilkS" user "Ref Des/Silkscreen Bottom")
		(1 "F.Mask" user "Board Geometry/Soldermask Top")
		(3 "B.Mask" user "Board Geometry/Soldermask Bottom")
		(17 "Dwgs.User" user "User.Drawings")
		(19 "Cmts.User" user "User.Comments")
		(21 "Eco1.User" user "User.Eco1")
		(23 "Eco2.User" user "User.Eco2")
		(25 "Edge.Cuts" user "Board Geometry/Outline")
		(27 "Margin" user)
		(31 "F.CrtYd" user "Package Geometry/Place Bound Top")
		(29 "B.CrtYd" user "Package Geometry/Place Bound Bottom")
		(35 "F.Fab" user "Ref Des/Assembly Top")
		(33 "B.Fab" user "Ref Des/Assembly Bottom")
	)
	(footprint ""
		(layer "F.Cu")
		(at 367.157 -411.226 -90)
		(property "Reference" "R6252"
			(at 0 0 270)
			(layer "F.SilkS")
			(hide yes)
			(effects
				(font
					(size 1.27 1.27)
				)
			)
		)
		(property "Value" ""
			(at 0 0 270)
			(layer "F.Fab")
			(effects
				(font
					(size 1.27 1.27)
				)
			)
		)
		(duplicate_pad_numbers_are_jumpers no)
		(fp_line
			(start -0.7874 0.4064)
			(end -0.7874 -0.4064)
			(stroke
				(width 0.1524)
				(type default)
			)
			(layer "F.SilkS")
		)
		(fp_line
			(start 0.7874 0.4064)
			(end -0.7874 0.4064)
			(stroke
				(width 0.1524)
				(type default)
			)
			(layer "F.SilkS")
		)
		(fp_line
			(start -0.7874 -0.4064)
			(end 0.7874 -0.4064)
			(stroke
				(width 0.1524)
				(type default)
			)
			(layer "F.SilkS")
		)
		(fp_line
			(start 0.7874 -0.4064)
			(end 0.7874 0.4064)
			(stroke
				(width 0.1524)
				(type default)
			)
			(layer "F.SilkS")
		)
		(fp_line
			(start -0.67945 0.3048)
			(end -0.67945 -0.305054)
			(stroke
				(width 0.1)
				(type default)
			)
			(layer "F.Fab")
		)
		(fp_line
			(start -0.12065 0.3048)
			(end -0.67945 0.3048)
			(stroke
				(width 0.1)
				(type default)
			)
			(layer "F.Fab")
		)
		(fp_line
			(start 0.120396 0.3048)
			(end 0.120396 0.2794)
			(stroke
				(width 0.1)
				(type default)
			)
			(layer "F.Fab")
		)
		(fp_line
			(start 0.67945 0.3048)
			(end 0.120396 0.3048)
			(stroke
				(width 0.1)
				(type default)
			)
			(layer "F.Fab")
		)
		(fp_line
			(start -0.12065 0.2794)
			(end -0.12065 0.3048)
			(stroke
				(width 0.1)
				(type default)
			)
			(layer "F.Fab")
		)
		(fp_line
			(start 0.120396 0.2794)
			(end -0.12065 0.2794)
			(stroke
				(width 0.1)
				(type default)
			)
			(layer "F.Fab")
		)
		(fp_line
			(start -0.12065 -0.2794)
			(end 0.12065 -0.2794)
			(stroke
				(width 0.1)
				(type default)
			)
			(layer "F.Fab")
		)
		(fp_line
			(start 0.12065 -0.2794)
			(end 0.12065 -0.3048)
			(stroke
				(width 0.1)
				(type default)
			)
			(layer "F.Fab")
		)
		(fp_line
			(start 0.12065 -0.3048)
			(end 0.67945 -0.3048)
			(stroke
				(width 0.1)
				(type default)
			)
			(layer "F.Fab")
		)
		(fp_line
			(start 0.67945 -0.3048)
			(end 0.67945 0.3048)
			(stroke
				(width 0.1)
				(type default)
			)
			(layer "F.Fab")
		)
		(fp_line
			(start -0.67945 -0.305054)
			(end -0.12065 -0.305054)
			(stroke
				(width 0.1)
				(type default)
			)
			(layer "F.Fab")
		)
		(fp_line
			(start -0.12065 -0.305054)
			(end -0.12065 -0.2794)
			(stroke
				(width 0.1)
				(type default)
			)
			(layer "F.Fab")
		)
		(pad "1" smd circle
			(at -0.40005 0 270)
			(size 0 0)
			(layers "F.Cu" "F.Mask" "F.Paste")
			(net "SMB_LM75_0_3V3AUX_SCL")
		)
		(pad "2" smd circle
			(at 0.40005 0 270)
			(size 0 0)
			(layers "F.Cu" "F.Mask" "F.Paste")
			(net "SMB_HSC_TYPE_ADC_SCL")
		)
	)
	(footprint ""
		(layer "F.Cu")
		(at 118.598696 -370.57203 -90)
		(property "Reference" "C1535"
			(at 0 0 270)
			(layer "F.SilkS")
			(hide yes)
			(effects
				(font
					(size 1.27 1.27)
				)
			)
		)
		(property "Value" ""
			(at 0 0 270)
			(layer "F.Fab")
			(effects
				(font
					(size 1.27 1.27)
				)
			)
		)
		(duplicate_pad_numbers_are_jumpers no)
		(fp_line
			(start -0.299974 0.150114)
			(end -0.299974 -0.150114)
			(stroke
				(width 0.1)
				(type default)
			)
			(layer "F.Fab")
		)
		(fp_line
			(start 0.299974 0.150114)
			(end -0.299974 0.150114)
			(stroke
				(width 0.1)
				(type default)
			)
			(layer "F.Fab")
		)
		(fp_line
			(start -0.299974 -0.150114)
			(end 0.299974 -0.150114)
			(stroke
				(width 0.1)
				(type default)
			)
			(layer "F.Fab")
		)
		(fp_line
			(start 0.299974 -0.150114)
			(end 0.299974 0.150114)
			(stroke
				(width 0.1)
				(type default)
			)
			(layer "F.Fab")
		)
		(pad "1" smd rect
			(at -0.2667 0 270)
			(size 0.3048 0.381)
			(layers "F.Cu" "F.Mask" "F.Paste")
			(net "P5E_CPU1_P3_TX_C_DP<6>")
		)
		(pad "2" smd rect
			(at 0.2667 0 270)
			(size 0.3048 0.381)
			(layers "F.Cu" "F.Mask" "F.Paste")
			(net "P5E_CPU1_P3_TX_DP<6>")
		)
	)
	(footprint ""
		(layer "F.Cu")
		(at 252.961648 -55.177182 180)
		(property "Reference" "PR3954"
			(at 0 0 180)
			(layer "F.SilkS")
			(hide yes)
			(effects
				(font
					(size 1.27 1.27)
				)
			)
		)
		(property "Value" ""
			(at 0 0 180)
			(layer "F.Fab")
			(effects
				(font
					(size 1.27 1.27)
				)
			)
		)
		(duplicate_pad_numbers_are_jumpers no)
		(fp_line
			(start 0.7874 0.4064)
			(end -0.7874 0.4064)
			(stroke
				(width 0.1524)
				(type default)
			)
			(layer "F.SilkS")
		)
		(fp_line
			(start 0.7874 -0.4064)
			(end 0.7874 0.4064)
			(stroke
				(width 0.1524)
				(type default)
			)
			(layer "F.SilkS")
		)
		(fp_line
			(start -0.7874 0.4064)
			(end -0.7874 -0.4064)
			(stroke
				(width 0.1524)
				(type default)
			)
			(layer "F.SilkS")
		)
		(fp_line
			(start -0.7874 -0.4064)
			(end 0.7874 -0.4064)
			(stroke
				(width 0.1524)
				(type default)
			)
			(layer "F.SilkS")
		)
		(fp_line
			(start 0.67945 0.3048)
			(end 0.120396 0.3048)
			(stroke
				(width 0.1)
				(type default)
			)
			(layer "F.Fab")
		)
		(fp_line
			(start 0.67945 -0.3048)
			(end 0.67945 0.3048)
			(stroke
				(width 0.1)
				(type default)
			)
			(layer "F.Fab")
		)
		(fp_line
			(start 0.12065 -0.2794)
			(end 0.12065 -0.3048)
			(stroke
				(width 0.1)
				(type default)
			)
			(layer "F.Fab")
		)
		(fp_line
			(start 0.12065 -0.3048)
			(end 0.67945 -0.3048)
			(stroke
				(width 0.1)
				(type default)
			)
			(layer "F.Fab")
		)
		(fp_line
			(start 0.120396 0.3048)
			(end 0.120396 0.2794)
			(stroke
				(width 0.1)
				(type default)
			)
			(layer "F.Fab")
		)
		(fp_line
			(start 0.120396 0.2794)
			(end -0.12065 0.2794)
			(stroke
				(width 0.1)
				(type default)
			)
			(layer "F.Fab")
		)
		(fp_line
			(start -0.12065 0.3048)
			(end -0.67945 0.3048)
			(stroke
				(width 0.1)
				(type default)
			)
			(layer "F.Fab")
		)
		(fp_line
			(start -0.12065 0.2794)
			(end -0.12065 0.3048)
			(stroke
				(width 0.1)
				(type default)
			)
			(layer "F.Fab")
		)
		(fp_line
			(start -0.12065 -0.2794)
			(end 0.12065 -0.2794)
			(stroke
				(width 0.1)
				(type default)
			)
			(layer "F.Fab")
		)
		(fp_line
			(start -0.12065 -0.305054)
			(end -0.12065 -0.2794)
			(stroke
				(width 0.1)
				(type default)
			)
			(layer "F.Fab")
		)
		(fp_line
			(start -0.67945 0.3048)
			(end -0.67945 -0.305054)
			(stroke
				(width 0.1)
				(type default)
			)
			(layer "F.Fab")
		)
		(fp_line
			(start -0.67945 -0.305054)
			(end -0.12065 -0.305054)
			(stroke
				(width 0.1)
				(type default)
			)
			(layer "F.Fab")
		)
		(pad "1" smd circle
			(at -0.40005 0 180)
			(size 0 0)
			(layers "F.Cu" "F.Mask" "F.Paste")
			(net "P12V_E1S_OV_FB_0")
		)
		(pad "2" smd circle
			(at 0.40005 0 180)
			(size 0 0)
			(layers "F.Cu" "F.Mask" "F.Paste")
			(net "GND")
		)
	)
	(footprint ""
		(layer "F.Cu")
		(at 304.523394 -408.801316 -90)
		(property "Reference" "C559"
			(at 0 0 270)
			(layer "F.SilkS")
			(hide yes)
			(effects
				(font
					(size 1.27 1.27)
				)
			)
		)
		(property "Value" ""
			(at 0 0 270)
			(layer "F.Fab")
			(effects
				(font
					(size 1.27 1.27)
				)
			)
		)
		(duplicate_pad_numbers_are_jumpers no)
		(fp_line
			(start -1.524 0.762)
			(end -1.524 -0.762)
			(stroke
				(width 0.1524)
				(type default)
			)
			(layer "F.SilkS")
		)
		(fp_line
			(start 1.524 0.762)
			(end -1.524 0.762)
			(stroke
				(width 0.1524)
				(type default)
			)
			(layer "F.SilkS")
		)
		(fp_line
			(start -1.524 -0.762)
			(end 1.524 -0.762)
			(stroke
				(width 0.1524)
				(type default)
			)
			(layer "F.SilkS")
		)
		(fp_line
			(start 1.524 -0.762)
			(end 1.524 0.762)
			(stroke
				(width 0.1524)
				(type default)
			)
			(layer "F.SilkS")
		)
		(fp_line
			(start -1.1049 0.724916)
			(end 1.1049 0.724916)
			(stroke
				(width 0.1)
				(type default)
			)
			(layer "F.Fab")
		)
		(fp_line
			(start 1.1049 0.724916)
			(end 1.1049 -0.724916)
			(stroke
				(width 0.1)
				(type default)
			)
			(layer "F.Fab")
		)
		(fp_line
			(start -1.1049 -0.724916)
			(end -1.1049 0.724916)
			(stroke
				(width 0.1)
				(type default)
			)
			(layer "F.Fab")
		)
		(fp_line
			(start 1.1049 -0.724916)
			(end -1.1049 -0.724916)
			(stroke
				(width 0.1)
				(type default)
			)
			(layer "F.Fab")
		)
		(pad "1" smd rect
			(at -0.889 0 90)
			(size 1.016 1.27)
			(layers "F.Cu" "F.Mask" "F.Paste")
			(net "P0V9_CPU0_RT_2D")
		)
		(pad "2" smd rect
			(at 0.889 0 90)
			(size 1.016 1.27)
			(layers "F.Cu" "F.Mask" "F.Paste")
			(net "GND")
		)
	)
	(footprint ""
		(layer "F.Cu")
		(at 331.494892 -384.32486 180)
		(property "Reference" "C963"
			(at 0 0 180)
			(layer "F.SilkS")
			(hide yes)
			(effects
				(font
					(size 1.27 1.27)
				)
			)
		)
		(property "Value" ""
			(at 0 0 180)
			(layer "F.Fab")
			(effects
				(font
					(size 1.27 1.27)
				)
			)
		)
		(duplicate_pad_numbers_are_jumpers no)
		(fp_line
			(start 0.299974 0.150114)
			(end -0.299974 0.150114)
			(stroke
				(width 0.1)
				(type default)
			)
			(layer "F.Fab")
		)
		(fp_line
			(start 0.299974 -0.150114)
			(end 0.299974 0.150114)
			(stroke
				(width 0.1)
				(type default)
			)
			(layer "F.Fab")
		)
		(fp_line
			(start -0.299974 0.150114)
			(end -0.299974 -0.150114)
			(stroke
				(width 0.1)
				(type default)
			)
			(layer "F.Fab")
		)
		(fp_line
			(start -0.299974 -0.150114)
			(end 0.299974 -0.150114)
			(stroke
				(width 0.1)
				(type default)
			)
			(layer "F.Fab")
		)
		(pad "1" smd rect
			(at -0.2667 0 180)
			(size 0.3048 0.381)
			(layers "F.Cu" "F.Mask" "F.Paste")
			(net "P5E_CPU0_P1_TX_C_DP<1>")
		)
		(pad "2" smd rect
			(at 0.2667 0 180)
			(size 0.3048 0.381)
			(layers "F.Cu" "F.Mask" "F.Paste")
			(net "P5E_CPU0_P1_TX_DP<1>")
		)
	)
	(footprint ""
		(layer "F.Cu")
		(at 401.128484 -403.818852 -90)
		(property "Reference" "R1080"
			(at 0 0 270)
			(layer "F.SilkS")
			(hide yes)
			(effects
				(font
					(size 1.27 1.27)
				)
			)
		)
		(property "Value" ""
			(at 0 0 270)
			(layer "F.Fab")
			(effects
				(font
					(size 1.27 1.27)
				)
			)
		)
		(duplicate_pad_numbers_are_jumpers no)
		(fp_line
			(start -0.32512 0.175006)
			(end -0.32512 -0.175006)
			(stroke
				(width 0.1)
				(type default)
			)
			(layer "F.Fab")
		)
		(fp_line
			(start 0.32512 0.175006)
			(end -0.32512 0.175006)
			(stroke
				(width 0.1)
				(type default)
			)
			(layer "F.Fab")
		)
		(fp_line
			(start -0.32512 -0.175006)
			(end 0.32512 -0.175006)
			(stroke
				(width 0.1)
				(type default)
			)
			(layer "F.Fab")
		)
		(fp_line
			(start 0.32512 -0.175006)
			(end 0.32512 0.175006)
			(stroke
				(width 0.1)
				(type default)
			)
			(layer "F.Fab")
		)
		(pad "1" smd rect
			(at -0.2667 0 270)
			(size 0.3048 0.381)
			(layers "F.Cu" "F.Mask" "F.Paste")
			(net "P1V8_CPU0_RT_1D")
		)
		(pad "2" smd rect
			(at 0.2667 0 90)
			(size 0.3048 0.381)
			(layers "F.Cu" "F.Mask" "F.Paste")
			(net "MODE_RT_CPU0_P2")
		)
	)
	(footprint ""
		(layer "F.Cu")
		(at 453.210676 -402.801328)
		(property "Reference" "PR6561"
			(at 0 0 0)
			(layer "F.SilkS")
			(hide yes)
			(effects
				(font
					(size 1.27 1.27)
				)
			)
		)
		(property "Value" ""
			(at 0 0 0)
			(layer "F.Fab")
			(effects
				(font
					(size 1.27 1.27)
				)
			)
		)
		(duplicate_pad_numbers_are_jumpers no)
		(fp_line
			(start -0.7874 -0.4064)
			(end 0.7874 -0.4064)
			(stroke
				(width 0.1524)
				(type default)
			)
			(layer "F.SilkS")
		)
		(fp_line
			(start -0.7874 0.4064)
			(end -0.7874 -0.4064)
			(stroke
				(width 0.1524)
				(type default)
			)
			(layer "F.SilkS")
		)
		(fp_line
			(start 0.7874 -0.4064)
			(end 0.7874 0.4064)
			(stroke
				(width 0.1524)
				(type default)
			)
			(layer "F.SilkS")
		)
		(fp_line
			(start 0.7874 0.4064)
			(end -0.7874 0.4064)
			(stroke
				(width 0.1524)
				(type default)
			)
			(layer "F.SilkS")
		)
		(fp_line
			(start -0.67945 -0.305054)
			(end -0.12065 -0.305054)
			(stroke
				(width 0.1)
				(type default)
			)
			(layer "F.Fab")
		)
		(fp_line
			(start -0.67945 0.3048)
			(end -0.67945 -0.305054)
			(stroke
				(width 0.1)
				(type default)
			)
			(layer "F.Fab")
		)
		(fp_line
			(start -0.12065 -0.305054)
			(end -0.12065 -0.2794)
			(stroke
				(width 0.1)
				(type default)
			)
			(layer "F.Fab")
		)
		(fp_line
			(start -0.12065 -0.2794)
			(end 0.12065 -0.2794)
			(stroke
				(width 0.1)
				(type default)
			)
			(layer "F.Fab")
		)
		(fp_line
			(start -0.12065 0.2794)
			(end -0.12065 0.3048)
			(stroke
				(width 0.1)
				(type default)
			)
			(layer "F.Fab")
		)
		(fp_line
			(start -0.12065 0.3048)
			(end -0.67945 0.3048)
			(stroke
				(width 0.1)
				(type default)
			)
			(layer "F.Fab")
		)
		(fp_line
			(start 0.120396 0.2794)
			(end -0.12065 0.2794)
			(stroke
				(width 0.1)
				(type default)
			)
			(layer "F.Fab")
		)
		(fp_line
			(start 0.120396 0.3048)
			(end 0.120396 0.2794)
			(stroke
				(width 0.1)
				(type default)
			)
			(layer "F.Fab")
		)
		(fp_line
			(start 0.12065 -0.3048)
			(end 0.67945 -0.3048)
			(stroke
				(width 0.1)
				(type default)
			)
			(layer "F.Fab")
		)
		(fp_line
			(start 0.12065 -0.2794)
			(end 0.12065 -0.3048)
			(stroke
				(width 0.1)
				(type default)
			)
			(layer "F.Fab")
		)
		(fp_line
			(start 0.67945 -0.3048)
			(end 0.67945 0.3048)
			(stroke
				(width 0.1)
				(type default)
			)
			(layer "F.Fab")
		)
		(fp_line
			(start 0.67945 0.3048)
			(end 0.120396 0.3048)
			(stroke
				(width 0.1)
				(type default)
			)
			(layer "F.Fab")
		)
		(pad "1" smd circle
			(at -0.40005 0)
			(size 0 0)
			(layers "F.Cu" "F.Mask" "F.Paste")
			(net "P0V9_RETIMER_CPU0_LSET2")
		)
		(pad "2" smd circle
			(at 0.40005 0)
			(size 0 0)
			(layers "F.Cu" "F.Mask" "F.Paste")
			(net "GND")
		)
	)
	(footprint ""
		(layer "F.Cu")
		(at 239.893602 -290.341812 89.946)
		(property "Reference" "PR6507"
			(at 0 0 89.946)
			(layer "F.SilkS")
			(hide yes)
			(effects
				(font
					(size 1.27 1.27)
				)
			)
		)
		(property "Value" ""
			(at 0 0 89.946)
			(layer "F.Fab")
			(effects
				(font
					(size 1.27 1.27)
				)
			)
		)
		(duplicate_pad_numbers_are_jumpers no)
		(fp_line
			(start -0.787275 -0.40642)
			(end 0.787525 -0.40638)
			(stroke
				(width 0.1524)
				(type default)
			)
			(layer "F.SilkS")
		)
		(fp_line
			(start 0.787525 -0.40638)
			(end 0.787275 0.40642)
			(stroke
				(width 0.1524)
				(type default)
			)
			(layer "F.SilkS")
		)
		(fp_line
			(start -0.787525 0.40638)
			(end -0.787275 -0.40642)
			(stroke
				(width 0.1524)
				(type default)
			)
			(layer "F.SilkS")
		)
		(fp_line
			(start 0.787275 0.40642)
			(end -0.787525 0.40638)
			(stroke
				(width 0.1524)
				(type default)
			)
			(layer "F.SilkS")
		)
		(fp_line
			(start -0.679484 -0.305176)
			(end -0.120683 -0.30494)
			(stroke
				(width 0.1)
				(type default)
			)
			(layer "F.Fab")
		)
		(fp_line
			(start -0.120683 -0.30494)
			(end -0.120659 -0.279286)
			(stroke
				(width 0.1)
				(type default)
			)
			(layer "F.Fab")
		)
		(fp_line
			(start 0.120617 -0.304914)
			(end 0.679417 -0.304678)
			(stroke
				(width 0.1)
				(type default)
			)
			(layer "F.Fab")
		)
		(fp_line
			(start 0.679417 -0.304678)
			(end 0.679484 0.304922)
			(stroke
				(width 0.1)
				(type default)
			)
			(layer "F.Fab")
		)
		(fp_line
			(start 0.120641 -0.279514)
			(end 0.120617 -0.304914)
			(stroke
				(width 0.1)
				(type default)
			)
			(layer "F.Fab")
		)
		(fp_line
			(start -0.120659 -0.279286)
			(end 0.120641 -0.279514)
			(stroke
				(width 0.1)
				(type default)
			)
			(layer "F.Fab")
		)
		(fp_line
			(start 0.120405 0.279287)
			(end -0.120641 0.279514)
			(stroke
				(width 0.1)
				(type default)
			)
			(layer "F.Fab")
		)
		(fp_line
			(start -0.120641 0.279514)
			(end -0.120617 0.304914)
			(stroke
				(width 0.1)
				(type default)
			)
			(layer "F.Fab")
		)
		(fp_line
			(start -0.679417 0.304678)
			(end -0.679484 -0.305176)
			(stroke
				(width 0.1)
				(type default)
			)
			(layer "F.Fab")
		)
		(fp_line
			(start 0.120429 0.304687)
			(end 0.120405 0.279287)
			(stroke
				(width 0.1)
				(type default)
			)
			(layer "F.Fab")
		)
		(fp_line
			(start -0.120617 0.304914)
			(end -0.679417 0.304678)
			(stroke
				(width 0.1)
				(type default)
			)
			(layer "F.Fab")
		)
		(fp_line
			(start 0.679484 0.304922)
			(end 0.120429 0.304687)
			(stroke
				(width 0.1)
				(type default)
			)
			(layer "F.Fab")
		)
		(pad "1" smd circle
			(at -0.40005 0 89.946)
			(size 0 0)
			(layers "F.Cu" "F.Mask" "F.Paste")
			(net "P1V8_RETIMER_CPU0_FB")
		)
		(pad "2" smd circle
			(at 0.40005 0 89.946)
			(size 0 0)
			(layers "F.Cu" "F.Mask" "F.Paste")
			(net "GND")
		)
	)
)
